(kicad_pcb
	(version 20221018)
	(generator pcbnew)
	(general
    (thickness 1.62)
  )
	(paper "A4")
	(title_block
    (title "ECP5 - Datacenter Secure Control Module (DC-SCM)")
    (date "2024-07-01")
    (rev "1.2.1")
		(comment 9 "footprints 328-335 of 506")
	)
	(layers
    (0 "F.Cu" signal)
    (1 "In1.Cu" power)
    (2 "In2.Cu" signal)
    (3 "In3.Cu" power)
    (4 "In4.Cu" power)
    (5 "In5.Cu" signal)
    (6 "In6.Cu" power)
    (31 "B.Cu" signal)
    (32 "B.Adhes" user "B.Adhesive")
    (33 "F.Adhes" user "F.Adhesive")
    (34 "B.Paste" user)
    (35 "F.Paste" user)
    (36 "B.SilkS" user "B.Silkscreen")
    (37 "F.SilkS" user "F.Silkscreen")
    (38 "B.Mask" user)
    (39 "F.Mask" user)
    (40 "Dwgs.User" user "User.Drawings")
    (41 "Cmts.User" user "User.Comments")
    (42 "Eco1.User" user "User.Eco1")
    (43 "Eco2.User" user "User.Eco2")
    (44 "Edge.Cuts" user)
    (45 "Margin" user)
    (46 "B.CrtYd" user "B.Courtyard")
    (47 "F.CrtYd" user "F.Courtyard")
    (48 "B.Fab" user)
    (49 "F.Fab" user)
  )
	(footprint "antmicro-footprints:C_0402_1005Metric" (layer "B.Cu")
    (at 109.2 121.75 -90)
    (descr "Capacitor SMD 0402")
    (tags "capacitor SMD 0402")
    (property "Author" "Antmicro")
    (property "Dielectric" "")
    (property "License" "Apache-2.0")
    (property "MPN" "C1005X5R1E474M050BB")
    (property "Manufacturer" "TDK")
    (property "Public" "False")
    (property "Sheetfile" "fpga-banks.kicad_sch")
    (property "Sheetname" "FPGA banks")
    (property "Val" "470n")
    (property "Voltage" "")
    (property "ki_description" "SMD Multilayer Ceramic Capacitor, 0.47 µF, 25 V, 0402 [1005 Metric], ± 20%, X5R, C")
    (property "ki_keywords" "0402, SMT, CAPACITOR, PASSIVE, CERAMIC, MLCC")
    (attr smd)
    (fp_text reference "C221" (at 22.8 -0.25 90) (layer "B.SilkS")
        (effects (font (size 0.7 0.7) (thickness 0.127)) (justify mirror))
    )
    (fp_text value "C_470n_0402" (at 0 -1.17 90) (layer "B.Fab")
        (effects (font (size 1 1) (thickness 0.15)) (justify mirror))
    )
    (fp_text user "${REFERENCE}" (at 0 0 90) (layer "B.Fab")
        (effects (font (size 0.25 0.25) (thickness 0.04)) (justify mirror))
    )
    (fp_text user "Author: Antmicro" (at -0.939 -3.399 90) (layer "B.Fab") hide
        (effects (font (size 0.7 0.7) (thickness 0.15)) (justify left bottom mirror))
    )
    (fp_text user "License: Apache-2.0" (at -0.939 -5.799 90) (layer "B.Fab") hide
        (effects (font (size 0.7 0.7) (thickness 0.15)) (justify left bottom mirror))
    )
    (fp_rect (start -0.925 0.47) (end 0.925 -0.47)
      (stroke (width 0.05) (type default)) (fill none) (layer "B.CrtYd"))
    (fp_line (start -0.494 -0.248) (end -0.494 0.25)
      (stroke (width 0.15) (type solid)) (layer "B.Fab"))
    (fp_line (start -0.494 0.25) (end 0.504 0.25)
      (stroke (width 0.15) (type solid)) (layer "B.Fab"))
    (fp_line (start 0.504 -0.248) (end -0.494 -0.248)
      (stroke (width 0.15) (type solid)) (layer "B.Fab"))
    (fp_line (start 0.504 0.25) (end 0.504 -0.248)
      (stroke (width 0.15) (type solid)) (layer "B.Fab"))
    (pad "1" smd roundrect (at -0.48 0 270) (size 0.59 0.64) (layers "B.Cu" "B.Paste" "B.Mask") (roundrect_rratio 0.25)
      (net 218 "VCC1V8") (pintype "passive"))
    (pad "2" smd roundrect (at 0.48 0 270) (size 0.59 0.64) (layers "B.Cu" "B.Paste" "B.Mask") (roundrect_rratio 0.25)
      (net 1 "GND") (pintype "passive"))
  )
	(footprint "antmicro-footprints:C_0402_1005Metric" (layer "B.Cu")
    (at 109.15 119.65 180)
    (descr "Capacitor SMD 0402")
    (tags "capacitor SMD 0402")
    (property "Author" "Antmicro")
    (property "Dielectric" "")
    (property "License" "Apache-2.0")
    (property "MPN" "C1005X5R1E474M050BB")
    (property "Manufacturer" "TDK")
    (property "Public" "False")
    (property "Sheetfile" "fpga-banks.kicad_sch")
    (property "Sheetname" "FPGA banks")
    (property "Val" "470n")
    (property "Voltage" "")
    (property "ki_description" "SMD Multilayer Ceramic Capacitor, 0.47 µF, 25 V, 0402 [1005 Metric], ± 20%, X5R, C")
    (property "ki_keywords" "0402, SMT, CAPACITOR, PASSIVE, CERAMIC, MLCC")
    (attr smd)
    (fp_text reference "C222" (at 0.05 -22.85) (layer "B.SilkS")
        (effects (font (size 0.7 0.7) (thickness 0.127)) (justify mirror))
    )
    (fp_text value "C_470n_0402" (at 0 -1.17) (layer "B.Fab")
        (effects (font (size 1 1) (thickness 0.15)) (justify mirror))
    )
    (fp_text user "${REFERENCE}" (at 0 0) (layer "B.Fab")
        (effects (font (size 0.25 0.25) (thickness 0.04)) (justify mirror))
    )
    (fp_text user "License: Apache-2.0" (at -0.939 -5.799) (layer "B.Fab") hide
        (effects (font (size 0.7 0.7) (thickness 0.15)) (justify left bottom mirror))
    )
    (fp_text user "Author: Antmicro" (at -0.939 -3.399) (layer "B.Fab") hide
        (effects (font (size 0.7 0.7) (thickness 0.15)) (justify left bottom mirror))
    )
    (fp_rect (start -0.925 0.47) (end 0.925 -0.47)
      (stroke (width 0.05) (type default)) (fill none) (layer "B.CrtYd"))
    (fp_line (start -0.494 -0.248) (end -0.494 0.25)
      (stroke (width 0.15) (type solid)) (layer "B.Fab"))
    (fp_line (start -0.494 0.25) (end 0.504 0.25)
      (stroke (width 0.15) (type solid)) (layer "B.Fab"))
    (fp_line (start 0.504 -0.248) (end -0.494 -0.248)
      (stroke (width 0.15) (type solid)) (layer "B.Fab"))
    (fp_line (start 0.504 0.25) (end 0.504 -0.248)
      (stroke (width 0.15) (type solid)) (layer "B.Fab"))
    (pad "1" smd roundrect (at -0.48 0 180) (size 0.59 0.64) (layers "B.Cu" "B.Paste" "B.Mask") (roundrect_rratio 0.25)
      (net 218 "VCC1V8") (pintype "passive"))
    (pad "2" smd roundrect (at 0.48 0 180) (size 0.59 0.64) (layers "B.Cu" "B.Paste" "B.Mask") (roundrect_rratio 0.25)
      (net 1 "GND") (pintype "passive"))
  )
	(footprint "antmicro-footprints:C_0402_1005Metric" (layer "B.Cu")
    (at 109.1 118.15 180)
    (descr "Capacitor SMD 0402")
    (tags "capacitor SMD 0402")
    (property "Author" "Antmicro")
    (property "Dielectric" "")
    (property "License" "Apache-2.0")
    (property "MPN" "C1005X5R1E474M050BB")
    (property "Manufacturer" "TDK")
    (property "Public" "False")
    (property "Sheetfile" "fpga-banks.kicad_sch")
    (property "Sheetname" "FPGA banks")
    (property "Val" "470n")
    (property "Voltage" "")
    (property "ki_description" "SMD Multilayer Ceramic Capacitor, 0.47 µF, 25 V, 0402 [1005 Metric], ± 20%, X5R, C")
    (property "ki_keywords" "0402, SMT, CAPACITOR, PASSIVE, CERAMIC, MLCC")
    (attr smd)
    (fp_text reference "C223" (at 0.05 -22.9) (layer "B.SilkS")
        (effects (font (size 0.7 0.7) (thickness 0.127)) (justify mirror))
    )
    (fp_text value "C_470n_0402" (at 0 -1.17) (layer "B.Fab")
        (effects (font (size 1 1) (thickness 0.15)) (justify mirror))
    )
    (fp_text user "License: Apache-2.0" (at -0.939 -5.799) (layer "B.Fab") hide
        (effects (font (size 0.7 0.7) (thickness 0.15)) (justify left bottom mirror))
    )
    (fp_text user "${REFERENCE}" (at 0 0) (layer "B.Fab")
        (effects (font (size 0.25 0.25) (thickness 0.04)) (justify mirror))
    )
    (fp_text user "Author: Antmicro" (at -0.939 -3.399) (layer "B.Fab") hide
        (effects (font (size 0.7 0.7) (thickness 0.15)) (justify left bottom mirror))
    )
    (fp_rect (start -0.925 0.47) (end 0.925 -0.47)
      (stroke (width 0.05) (type default)) (fill none) (layer "B.CrtYd"))
    (fp_line (start -0.494 -0.248) (end -0.494 0.25)
      (stroke (width 0.15) (type solid)) (layer "B.Fab"))
    (fp_line (start -0.494 0.25) (end 0.504 0.25)
      (stroke (width 0.15) (type solid)) (layer "B.Fab"))
    (fp_line (start 0.504 -0.248) (end -0.494 -0.248)
      (stroke (width 0.15) (type solid)) (layer "B.Fab"))
    (fp_line (start 0.504 0.25) (end 0.504 -0.248)
      (stroke (width 0.15) (type solid)) (layer "B.Fab"))
    (pad "1" smd roundrect (at -0.48 0 180) (size 0.59 0.64) (layers "B.Cu" "B.Paste" "B.Mask") (roundrect_rratio 0.25)
      (net 218 "VCC1V8") (pintype "passive"))
    (pad "2" smd roundrect (at 0.48 0 180) (size 0.59 0.64) (layers "B.Cu" "B.Paste" "B.Mask") (roundrect_rratio 0.25)
      (net 1 "GND") (pintype "passive"))
  )
	(footprint "antmicro-footprints:C_0402_1005Metric" (layer "B.Cu")
    (at 110.5 116.05)
    (descr "Capacitor SMD 0402")
    (tags "capacitor SMD 0402")
    (property "Author" "Antmicro")
    (property "Dielectric" "")
    (property "License" "Apache-2.0")
    (property "MPN" "C1005X5R1E474M050BB")
    (property "Manufacturer" "TDK")
    (property "Public" "False")
    (property "Sheetfile" "fpga-banks.kicad_sch")
    (property "Sheetname" "FPGA banks")
    (property "Val" "470n")
    (property "Voltage" "")
    (property "ki_description" "SMD Multilayer Ceramic Capacitor, 0.47 µF, 25 V, 0402 [1005 Metric], ± 20%, X5R, C")
    (property "ki_keywords" "0402, SMT, CAPACITOR, PASSIVE, CERAMIC, MLCC")
    (attr smd)
    (fp_text reference "C224" (at 2.55 -0.05) (layer "B.SilkS")
        (effects (font (size 0.7 0.7) (thickness 0.127)) (justify mirror))
    )
    (fp_text value "C_470n_0402" (at 0 -1.17) (layer "B.Fab")
        (effects (font (size 1 1) (thickness 0.15)) (justify mirror))
    )
    (fp_text user "License: Apache-2.0" (at -0.939 -5.799 180) (layer "B.Fab") hide
        (effects (font (size 0.7 0.7) (thickness 0.15)) (justify left bottom mirror))
    )
    (fp_text user "${REFERENCE}" (at 0 0) (layer "B.Fab")
        (effects (font (size 0.25 0.25) (thickness 0.04)) (justify mirror))
    )
    (fp_text user "Author: Antmicro" (at -0.939 -3.399 180) (layer "B.Fab") hide
        (effects (font (size 0.7 0.7) (thickness 0.15)) (justify left bottom mirror))
    )
    (fp_rect (start -0.925 0.47) (end 0.925 -0.47)
      (stroke (width 0.05) (type default)) (fill none) (layer "B.CrtYd"))
    (fp_line (start -0.494 -0.248) (end -0.494 0.25)
      (stroke (width 0.15) (type solid)) (layer "B.Fab"))
    (fp_line (start -0.494 0.25) (end 0.504 0.25)
      (stroke (width 0.15) (type solid)) (layer "B.Fab"))
    (fp_line (start 0.504 -0.248) (end -0.494 -0.248)
      (stroke (width 0.15) (type solid)) (layer "B.Fab"))
    (fp_line (start 0.504 0.25) (end 0.504 -0.248)
      (stroke (width 0.15) (type solid)) (layer "B.Fab"))
    (pad "1" smd roundrect (at -0.48 0) (size 0.59 0.64) (layers "B.Cu" "B.Paste" "B.Mask") (roundrect_rratio 0.25)
      (net 218 "VCC1V8") (pintype "passive"))
    (pad "2" smd roundrect (at 0.48 0) (size 0.59 0.64) (layers "B.Cu" "B.Paste" "B.Mask") (roundrect_rratio 0.25)
      (net 1 "GND") (pintype "passive"))
  )
	(footprint "antmicro-footprints:C_0402_1005Metric" (layer "B.Cu")
    (at 111.25 119.65)
    (descr "Capacitor SMD 0402")
    (tags "capacitor SMD 0402")
    (property "Author" "Antmicro")
    (property "Dielectric" "")
    (property "License" "Apache-2.0")
    (property "MPN" "GRM155R61A475MEAAD")
    (property "Manufacturer" "Murata")
    (property "Public" "False")
    (property "Sheetfile" "fpga-banks.kicad_sch")
    (property "Sheetname" "FPGA banks")
    (property "Val" "4u7")
    (property "Voltage" "")
    (property "ki_description" "SMD Multilayer Ceramic Capacitor, 4.7 µF, 10 V, 0402 [1005 Metric], ± 20%, X5R, GRM Series")
    (property "ki_keywords" "0402, SMT, CAPACITOR, PASSIVE")
    (attr smd)
    (fp_text reference "C225" (at 2.4 -0.05) (layer "B.SilkS")
        (effects (font (size 0.7 0.7) (thickness 0.127)) (justify mirror))
    )
    (fp_text value "C_4u7_0402" (at 0 -1.17) (layer "B.Fab")
        (effects (font (size 1 1) (thickness 0.15)) (justify mirror))
    )
    (fp_text user "Author: Antmicro" (at -0.939 -3.399 180) (layer "B.Fab") hide
        (effects (font (size 0.7 0.7) (thickness 0.15)) (justify left bottom mirror))
    )
    (fp_text user "${REFERENCE}" (at 0 0) (layer "B.Fab")
        (effects (font (size 0.25 0.25) (thickness 0.04)) (justify mirror))
    )
    (fp_text user "License: Apache-2.0" (at -0.939 -5.799 180) (layer "B.Fab") hide
        (effects (font (size 0.7 0.7) (thickness 0.15)) (justify left bottom mirror))
    )
    (fp_rect (start -0.925 0.47) (end 0.925 -0.47)
      (stroke (width 0.05) (type default)) (fill none) (layer "B.CrtYd"))
    (fp_line (start -0.494 -0.248) (end -0.494 0.25)
      (stroke (width 0.15) (type solid)) (layer "B.Fab"))
    (fp_line (start -0.494 0.25) (end 0.504 0.25)
      (stroke (width 0.15) (type solid)) (layer "B.Fab"))
    (fp_line (start 0.504 -0.248) (end -0.494 -0.248)
      (stroke (width 0.15) (type solid)) (layer "B.Fab"))
    (fp_line (start 0.504 0.25) (end 0.504 -0.248)
      (stroke (width 0.15) (type solid)) (layer "B.Fab"))
    (pad "1" smd roundrect (at -0.48 0) (size 0.59 0.64) (layers "B.Cu" "B.Paste" "B.Mask") (roundrect_rratio 0.25)
      (net 2 "VCC3V3") (pintype "passive"))
    (pad "2" smd roundrect (at 0.48 0) (size 0.59 0.64) (layers "B.Cu" "B.Paste" "B.Mask") (roundrect_rratio 0.25)
      (net 1 "GND") (pintype "passive"))
  )
	(footprint "antmicro-footprints:C_0402_1005Metric" (layer "B.Cu")
    (at 111.25 123.75)
    (descr "Capacitor SMD 0402")
    (tags "capacitor SMD 0402")
    (property "Author" "Antmicro")
    (property "Dielectric" "")
    (property "License" "Apache-2.0")
    (property "MPN" "C1005X5R1E474M050BB")
    (property "Manufacturer" "TDK")
    (property "Public" "False")
    (property "Sheetfile" "fpga-banks.kicad_sch")
    (property "Sheetname" "FPGA banks")
    (property "Val" "470n")
    (property "Voltage" "")
    (property "ki_description" "SMD Multilayer Ceramic Capacitor, 0.47 µF, 25 V, 0402 [1005 Metric], ± 20%, X5R, C")
    (property "ki_keywords" "0402, SMT, CAPACITOR, PASSIVE, CERAMIC, MLCC")
    (attr smd)
    (fp_text reference "C226" (at 2.5 -0.05) (layer "B.SilkS")
        (effects (font (size 0.7 0.7) (thickness 0.127)) (justify mirror))
    )
    (fp_text value "C_470n_0402" (at 0 -1.17) (layer "B.Fab")
        (effects (font (size 1 1) (thickness 0.15)) (justify mirror))
    )
    (fp_text user "Author: Antmicro" (at -0.939 -3.399 180) (layer "B.Fab") hide
        (effects (font (size 0.7 0.7) (thickness 0.15)) (justify left bottom mirror))
    )
    (fp_text user "License: Apache-2.0" (at -0.939 -5.799 180) (layer "B.Fab") hide
        (effects (font (size 0.7 0.7) (thickness 0.15)) (justify left bottom mirror))
    )
    (fp_text user "${REFERENCE}" (at 0 0) (layer "B.Fab")
        (effects (font (size 0.25 0.25) (thickness 0.04)) (justify mirror))
    )
    (fp_rect (start -0.925 0.47) (end 0.925 -0.47)
      (stroke (width 0.05) (type default)) (fill none) (layer "B.CrtYd"))
    (fp_line (start -0.494 -0.248) (end -0.494 0.25)
      (stroke (width 0.15) (type solid)) (layer "B.Fab"))
    (fp_line (start -0.494 0.25) (end 0.504 0.25)
      (stroke (width 0.15) (type solid)) (layer "B.Fab"))
    (fp_line (start 0.504 -0.248) (end -0.494 -0.248)
      (stroke (width 0.15) (type solid)) (layer "B.Fab"))
    (fp_line (start 0.504 0.25) (end 0.504 -0.248)
      (stroke (width 0.15) (type solid)) (layer "B.Fab"))
    (pad "1" smd roundrect (at -0.48 0) (size 0.59 0.64) (layers "B.Cu" "B.Paste" "B.Mask") (roundrect_rratio 0.25)
      (net 2 "VCC3V3") (pintype "passive"))
    (pad "2" smd roundrect (at 0.48 0) (size 0.59 0.64) (layers "B.Cu" "B.Paste" "B.Mask") (roundrect_rratio 0.25)
      (net 1 "GND") (pintype "passive"))
  )
	(footprint "antmicro-footprints:C_0402_1005Metric" (layer "B.Cu")
    (at 111.25 121.7)
    (descr "Capacitor SMD 0402")
    (tags "capacitor SMD 0402")
    (property "Author" "Antmicro")
    (property "Dielectric" "")
    (property "License" "Apache-2.0")
    (property "MPN" "C1005X5R1E474M050BB")
    (property "Manufacturer" "TDK")
    (property "Public" "False")
    (property "Sheetfile" "fpga-banks.kicad_sch")
    (property "Sheetname" "FPGA banks")
    (property "Val" "470n")
    (property "Voltage" "")
    (property "ki_description" "SMD Multilayer Ceramic Capacitor, 0.47 µF, 25 V, 0402 [1005 Metric], ± 20%, X5R, C")
    (property "ki_keywords" "0402, SMT, CAPACITOR, PASSIVE, CERAMIC, MLCC")
    (attr smd)
    (fp_text reference "C228" (at 2.45 -0.05) (layer "B.SilkS")
        (effects (font (size 0.7 0.7) (thickness 0.127)) (justify mirror))
    )
    (fp_text value "C_470n_0402" (at 0 -1.17) (layer "B.Fab")
        (effects (font (size 1 1) (thickness 0.15)) (justify mirror))
    )
    (fp_text user "License: Apache-2.0" (at -0.939 -5.799 180) (layer "B.Fab") hide
        (effects (font (size 0.7 0.7) (thickness 0.15)) (justify left bottom mirror))
    )
    (fp_text user "${REFERENCE}" (at 0 0) (layer "B.Fab")
        (effects (font (size 0.25 0.25) (thickness 0.04)) (justify mirror))
    )
    (fp_text user "Author: Antmicro" (at -0.939 -3.399 180) (layer "B.Fab") hide
        (effects (font (size 0.7 0.7) (thickness 0.15)) (justify left bottom mirror))
    )
    (fp_rect (start -0.925 0.47) (end 0.925 -0.47)
      (stroke (width 0.05) (type default)) (fill none) (layer "B.CrtYd"))
    (fp_line (start -0.494 -0.248) (end -0.494 0.25)
      (stroke (width 0.15) (type solid)) (layer "B.Fab"))
    (fp_line (start -0.494 0.25) (end 0.504 0.25)
      (stroke (width 0.15) (type solid)) (layer "B.Fab"))
    (fp_line (start 0.504 -0.248) (end -0.494 -0.248)
      (stroke (width 0.15) (type solid)) (layer "B.Fab"))
    (fp_line (start 0.504 0.25) (end 0.504 -0.248)
      (stroke (width 0.15) (type solid)) (layer "B.Fab"))
    (pad "1" smd roundrect (at -0.48 0) (size 0.59 0.64) (layers "B.Cu" "B.Paste" "B.Mask") (roundrect_rratio 0.25)
      (net 2 "VCC3V3") (pintype "passive"))
    (pad "2" smd roundrect (at 0.48 0) (size 0.59 0.64) (layers "B.Cu" "B.Paste" "B.Mask") (roundrect_rratio 0.25)
      (net 1 "GND") (pintype "passive"))
  )
	(footprint "antmicro-footprints:C_0402_1005Metric" (layer "B.Cu")
    (at 111.25 120.675)
    (descr "Capacitor SMD 0402")
    (tags "capacitor SMD 0402")
    (property "Author" "Antmicro")
    (property "Dielectric" "")
    (property "License" "Apache-2.0")
    (property "MPN" "C1005X5R1E474M050BB")
    (property "Manufacturer" "TDK")
    (property "Public" "False")
    (property "Sheetfile" "fpga-banks.kicad_sch")
    (property "Sheetname" "FPGA banks")
    (property "Val" "470n")
    (property "Voltage" "")
    (property "ki_description" "SMD Multilayer Ceramic Capacitor, 0.47 µF, 25 V, 0402 [1005 Metric], ± 20%, X5R, C")
    (property "ki_keywords" "0402, SMT, CAPACITOR, PASSIVE, CERAMIC, MLCC")
    (attr smd)
    (fp_text reference "C229" (at 2.4 -0.075) (layer "B.SilkS")
        (effects (font (size 0.7 0.7) (thickness 0.127)) (justify mirror))
    )
    (fp_text value "C_470n_0402" (at 0 -1.17) (layer "B.Fab")
        (effects (font (size 1 1) (thickness 0.15)) (justify mirror))
    )
    (fp_text user "Author: Antmicro" (at -0.939 -3.399 180) (layer "B.Fab") hide
        (effects (font (size 0.7 0.7) (thickness 0.15)) (justify left bottom mirror))
    )
    (fp_text user "${REFERENCE}" (at 0 0) (layer "B.Fab")
        (effects (font (size 0.25 0.25) (thickness 0.04)) (justify mirror))
    )
    (fp_text user "License: Apache-2.0" (at -0.939 -5.799 180) (layer "B.Fab") hide
        (effects (font (size 0.7 0.7) (thickness 0.15)) (justify left bottom mirror))
    )
    (fp_rect (start -0.925 0.47) (end 0.925 -0.47)
      (stroke (width 0.05) (type default)) (fill none) (layer "B.CrtYd"))
    (fp_line (start -0.494 -0.248) (end -0.494 0.25)
      (stroke (width 0.15) (type solid)) (layer "B.Fab"))
    (fp_line (start -0.494 0.25) (end 0.504 0.25)
      (stroke (width 0.15) (type solid)) (layer "B.Fab"))
    (fp_line (start 0.504 -0.248) (end -0.494 -0.248)
      (stroke (width 0.15) (type solid)) (layer "B.Fab"))
    (fp_line (start 0.504 0.25) (end 0.504 -0.248)
      (stroke (width 0.15) (type solid)) (layer "B.Fab"))
    (pad "1" smd roundrect (at -0.48 0) (size 0.59 0.64) (layers "B.Cu" "B.Paste" "B.Mask") (roundrect_rratio 0.25)
      (net 2 "VCC3V3") (pintype "passive"))
    (pad "2" smd roundrect (at 0.48 0) (size 0.59 0.64) (layers "B.Cu" "B.Paste" "B.Mask") (roundrect_rratio 0.25)
      (net 1 "GND") (pintype "passive"))
  )
)
